(kicad_pcb
	(version 20260206)
	(generator "pcbnew")
	(generator_version "10.0")
	(general
		(thickness 1.6)
		(legacy_teardrops no)
	)
	(paper "A4")
	(title_block
		(title "9054_F0T_PDB_BD_GPU_F_V04_1213_1550_OCP.brd")
		(comment 1 "Grand Teton / footprints 404-409 of 608")
	)
	(layers
		(0 "F.Cu" signal "TOP")
		(4 "In1.Cu" signal "GND")
		(6 "In2.Cu" signal "IN1")
		(8 "In3.Cu" signal "GND1")
		(10 "In4.Cu" signal "VCC")
		(12 "In5.Cu" signal "VCC1")
		(14 "In6.Cu" signal "GND2")
		(16 "In7.Cu" signal "IN2")
		(18 "In8.Cu" signal "GND3")
		(2 "B.Cu" signal "BOTTOM")
		(9 "F.Adhes" user "F.Adhesive")
		(11 "B.Adhes" user "B.Adhesive")
		(13 "F.Paste" user "Package Geometry/Pastemask Top")
		(15 "B.Paste" user "Package Geometry/Pastemask Bottom")
		(5 "F.SilkS" user "Ref Des/Silkscreen Top")
		(7 "B.SilkS" user "Ref Des/Silkscreen Bottom")
		(1 "F.Mask" user "Board Geometry/Soldermask Top")
		(3 "B.Mask" user "Board Geometry/Soldermask Bottom")
		(17 "Dwgs.User" user "User.Drawings")
		(19 "Cmts.User" user "User.Comments")
		(21 "Eco1.User" user "User.Eco1")
		(23 "Eco2.User" user "User.Eco2")
		(25 "Edge.Cuts" user "Board Geometry/Outline")
		(27 "Margin" user)
		(31 "F.CrtYd" user "Package Geometry/Place Bound Top")
		(29 "B.CrtYd" user "Package Geometry/Place Bound Bottom")
		(35 "F.Fab" user "Ref Des/Assembly Top")
		(33 "B.Fab" user "Ref Des/Assembly Bottom")
	)
	(footprint ""
		(layer "B.Cu")
		(at 413.639 -35.306)
		(property "Reference" "R5938"
			(at 0 0 0)
			(layer "B.SilkS")
			(hide yes)
			(effects
				(font
					(size 1.27 1.27)
				)
				(justify mirror)
			)
		)
		(property "Value" ""
			(at 0 0 0)
			(layer "B.Fab")
			(effects
				(font
					(size 1.27 1.27)
				)
				(justify mirror)
			)
		)
		(duplicate_pad_numbers_are_jumpers no)
		(fp_line
			(start -0.7874 -0.4064)
			(end -0.7874 0.4064)
			(stroke
				(width 0.1524)
				(type default)
			)
			(layer "B.SilkS")
		)
		(fp_line
			(start -0.7874 0.4064)
			(end 0.7874 0.4064)
			(stroke
				(width 0.1524)
				(type default)
			)
			(layer "B.SilkS")
		)
		(fp_line
			(start 0.7874 -0.4064)
			(end -0.7874 -0.4064)
			(stroke
				(width 0.1524)
				(type default)
			)
			(layer "B.SilkS")
		)
		(fp_line
			(start 0.7874 0.4064)
			(end 0.7874 -0.4064)
			(stroke
				(width 0.1524)
				(type default)
			)
			(layer "B.SilkS")
		)
		(fp_line
			(start -0.67945 -0.3048)
			(end -0.67945 0.3048)
			(stroke
				(width 0.1)
				(type default)
			)
			(layer "B.Fab")
		)
		(fp_line
			(start -0.67945 0.3048)
			(end -0.120396 0.3048)
			(stroke
				(width 0.1)
				(type default)
			)
			(layer "B.Fab")
		)
		(fp_line
			(start -0.12065 -0.3048)
			(end -0.67945 -0.3048)
			(stroke
				(width 0.1)
				(type default)
			)
			(layer "B.Fab")
		)
		(fp_line
			(start -0.12065 -0.2794)
			(end -0.12065 -0.3048)
			(stroke
				(width 0.1)
				(type default)
			)
			(layer "B.Fab")
		)
		(fp_line
			(start -0.120396 0.2794)
			(end 0.12065 0.2794)
			(stroke
				(width 0.1)
				(type default)
			)
			(layer "B.Fab")
		)
		(fp_line
			(start -0.120396 0.3048)
			(end -0.120396 0.2794)
			(stroke
				(width 0.1)
				(type default)
			)
			(layer "B.Fab")
		)
		(fp_line
			(start 0.12065 -0.305054)
			(end 0.12065 -0.2794)
			(stroke
				(width 0.1)
				(type default)
			)
			(layer "B.Fab")
		)
		(fp_line
			(start 0.12065 -0.2794)
			(end -0.12065 -0.2794)
			(stroke
				(width 0.1)
				(type default)
			)
			(layer "B.Fab")
		)
		(fp_line
			(start 0.12065 0.2794)
			(end 0.12065 0.3048)
			(stroke
				(width 0.1)
				(type default)
			)
			(layer "B.Fab")
		)
		(fp_line
			(start 0.12065 0.3048)
			(end 0.67945 0.3048)
			(stroke
				(width 0.1)
				(type default)
			)
			(layer "B.Fab")
		)
		(fp_line
			(start 0.67945 -0.305054)
			(end 0.12065 -0.305054)
			(stroke
				(width 0.1)
				(type default)
			)
			(layer "B.Fab")
		)
		(fp_line
			(start 0.67945 0.3048)
			(end 0.67945 -0.305054)
			(stroke
				(width 0.1)
				(type default)
			)
			(layer "B.Fab")
		)
		(pad "1" smd circle
			(at 0.40005 0 180)
			(size 0 0)
			(layers "B.Cu" "B.Mask" "B.Paste")
			(net "PCA9555_2_A1")
		)
		(pad "2" smd circle
			(at -0.40005 0 180)
			(size 0 0)
			(layers "B.Cu" "B.Mask" "B.Paste")
			(net "GND")
		)
	)
	(footprint ""
		(layer "B.Cu")
		(at 180.086 -52.832)
		(property "Reference" "R5897"
			(at 0 0 0)
			(layer "B.SilkS")
			(hide yes)
			(effects
				(font
					(size 1.27 1.27)
				)
				(justify mirror)
			)
		)
		(property "Value" ""
			(at 0 0 0)
			(layer "B.Fab")
			(effects
				(font
					(size 1.27 1.27)
				)
				(justify mirror)
			)
		)
		(duplicate_pad_numbers_are_jumpers no)
		(fp_line
			(start -0.7874 -0.4064)
			(end -0.7874 0.4064)
			(stroke
				(width 0.1524)
				(type default)
			)
			(layer "B.SilkS")
		)
		(fp_line
			(start -0.7874 0.4064)
			(end 0.7874 0.4064)
			(stroke
				(width 0.1524)
				(type default)
			)
			(layer "B.SilkS")
		)
		(fp_line
			(start 0.7874 -0.4064)
			(end -0.7874 -0.4064)
			(stroke
				(width 0.1524)
				(type default)
			)
			(layer "B.SilkS")
		)
		(fp_line
			(start 0.7874 0.4064)
			(end 0.7874 -0.4064)
			(stroke
				(width 0.1524)
				(type default)
			)
			(layer "B.SilkS")
		)
		(fp_line
			(start -0.67945 -0.3048)
			(end -0.67945 0.3048)
			(stroke
				(width 0.1)
				(type default)
			)
			(layer "B.Fab")
		)
		(fp_line
			(start -0.67945 0.3048)
			(end -0.120396 0.3048)
			(stroke
				(width 0.1)
				(type default)
			)
			(layer "B.Fab")
		)
		(fp_line
			(start -0.12065 -0.3048)
			(end -0.67945 -0.3048)
			(stroke
				(width 0.1)
				(type default)
			)
			(layer "B.Fab")
		)
		(fp_line
			(start -0.12065 -0.2794)
			(end -0.12065 -0.3048)
			(stroke
				(width 0.1)
				(type default)
			)
			(layer "B.Fab")
		)
		(fp_line
			(start -0.120396 0.2794)
			(end 0.12065 0.2794)
			(stroke
				(width 0.1)
				(type default)
			)
			(layer "B.Fab")
		)
		(fp_line
			(start -0.120396 0.3048)
			(end -0.120396 0.2794)
			(stroke
				(width 0.1)
				(type default)
			)
			(layer "B.Fab")
		)
		(fp_line
			(start 0.12065 -0.305054)
			(end 0.12065 -0.2794)
			(stroke
				(width 0.1)
				(type default)
			)
			(layer "B.Fab")
		)
		(fp_line
			(start 0.12065 -0.2794)
			(end -0.12065 -0.2794)
			(stroke
				(width 0.1)
				(type default)
			)
			(layer "B.Fab")
		)
		(fp_line
			(start 0.12065 0.2794)
			(end 0.12065 0.3048)
			(stroke
				(width 0.1)
				(type default)
			)
			(layer "B.Fab")
		)
		(fp_line
			(start 0.12065 0.3048)
			(end 0.67945 0.3048)
			(stroke
				(width 0.1)
				(type default)
			)
			(layer "B.Fab")
		)
		(fp_line
			(start 0.67945 -0.305054)
			(end 0.12065 -0.305054)
			(stroke
				(width 0.1)
				(type default)
			)
			(layer "B.Fab")
		)
		(fp_line
			(start 0.67945 0.3048)
			(end 0.67945 -0.305054)
			(stroke
				(width 0.1)
				(type default)
			)
			(layer "B.Fab")
		)
		(pad "1" smd circle
			(at 0.40005 0 180)
			(size 0 0)
			(layers "B.Cu" "B.Mask" "B.Paste")
			(net "FM_HS2_EN_FUSE")
		)
		(pad "2" smd circle
			(at -0.40005 0 180)
			(size 0 0)
			(layers "B.Cu" "B.Mask" "B.Paste")
			(net "GND")
		)
	)
	(footprint ""
		(layer "B.Cu")
		(at 171.7294 -63.754 90)
		(property "Reference" "PC577"
			(at 0 0 90)
			(layer "B.SilkS")
			(hide yes)
			(effects
				(font
					(size 1.27 1.27)
				)
				(justify mirror)
			)
		)
		(property "Value" ""
			(at 0 0 90)
			(layer "B.Fab")
			(effects
				(font
					(size 1.27 1.27)
				)
				(justify mirror)
			)
		)
		(duplicate_pad_numbers_are_jumpers no)
		(fp_line
			(start 0.7874 -0.4064)
			(end -0.7874 -0.4064)
			(stroke
				(width 0.1524)
				(type default)
			)
			(layer "B.SilkS")
		)
		(fp_line
			(start -0.7874 -0.4064)
			(end -0.7874 0.4064)
			(stroke
				(width 0.1524)
				(type default)
			)
			(layer "B.SilkS")
		)
		(fp_line
			(start 0.7874 0.4064)
			(end 0.7874 -0.4064)
			(stroke
				(width 0.1524)
				(type default)
			)
			(layer "B.SilkS")
		)
		(fp_line
			(start -0.7874 0.4064)
			(end 0.7874 0.4064)
			(stroke
				(width 0.1524)
				(type default)
			)
			(layer "B.SilkS")
		)
		(fp_line
			(start 0.67945 -0.305054)
			(end 0.12065 -0.305054)
			(stroke
				(width 0.1)
				(type default)
			)
			(layer "B.Fab")
		)
		(fp_line
			(start 0.12065 -0.305054)
			(end 0.12065 -0.2794)
			(stroke
				(width 0.1)
				(type default)
			)
			(layer "B.Fab")
		)
		(fp_line
			(start -0.12065 -0.3048)
			(end -0.67945 -0.3048)
			(stroke
				(width 0.1)
				(type default)
			)
			(layer "B.Fab")
		)
		(fp_line
			(start -0.67945 -0.3048)
			(end -0.67945 0.3048)
			(stroke
				(width 0.1)
				(type default)
			)
			(layer "B.Fab")
		)
		(fp_line
			(start 0.12065 -0.2794)
			(end -0.12065 -0.2794)
			(stroke
				(width 0.1)
				(type default)
			)
			(layer "B.Fab")
		)
		(fp_line
			(start -0.12065 -0.2794)
			(end -0.12065 -0.3048)
			(stroke
				(width 0.1)
				(type default)
			)
			(layer "B.Fab")
		)
		(fp_line
			(start 0.12065 0.2794)
			(end 0.12065 0.3048)
			(stroke
				(width 0.1)
				(type default)
			)
			(layer "B.Fab")
		)
		(fp_line
			(start -0.120396 0.2794)
			(end 0.12065 0.2794)
			(stroke
				(width 0.1)
				(type default)
			)
			(layer "B.Fab")
		)
		(fp_line
			(start 0.67945 0.3048)
			(end 0.67945 -0.305054)
			(stroke
				(width 0.1)
				(type default)
			)
			(layer "B.Fab")
		)
		(fp_line
			(start 0.12065 0.3048)
			(end 0.67945 0.3048)
			(stroke
				(width 0.1)
				(type default)
			)
			(layer "B.Fab")
		)
		(fp_line
			(start -0.120396 0.3048)
			(end -0.120396 0.2794)
			(stroke
				(width 0.1)
				(type default)
			)
			(layer "B.Fab")
		)
		(fp_line
			(start -0.67945 0.3048)
			(end -0.120396 0.3048)
			(stroke
				(width 0.1)
				(type default)
			)
			(layer "B.Fab")
		)
		(pad "1" smd circle
			(at 0.40005 0 270)
			(size 0 0)
			(layers "B.Cu" "B.Mask" "B.Paste")
			(net "P52V_HS2_OV")
		)
		(pad "2" smd circle
			(at -0.40005 0 270)
			(size 0 0)
			(layers "B.Cu" "B.Mask" "B.Paste")
			(net "GND1_FIELD_SIGNAL")
		)
	)
	(footprint ""
		(layer "B.Cu")
		(at 175.179736 -56.007 -90)
		(property "Reference" "PR6978"
			(at 0 0 90)
			(layer "B.SilkS")
			(hide yes)
			(effects
				(font
					(size 1.27 1.27)
				)
				(justify mirror)
			)
		)
		(property "Value" ""
			(at 0 0 90)
			(layer "B.Fab")
			(effects
				(font
					(size 1.27 1.27)
				)
				(justify mirror)
			)
		)
		(duplicate_pad_numbers_are_jumpers no)
		(fp_line
			(start -1.651 0.8382)
			(end 1.651 0.8382)
			(stroke
				(width 0.1524)
				(type default)
			)
			(layer "B.SilkS")
		)
		(fp_line
			(start 1.651 0.8382)
			(end 1.651 -0.8382)
			(stroke
				(width 0.1524)
				(type default)
			)
			(layer "B.SilkS")
		)
		(fp_line
			(start -1.651 -0.8382)
			(end -1.651 0.8382)
			(stroke
				(width 0.1524)
				(type default)
			)
			(layer "B.SilkS")
		)
		(fp_line
			(start 1.651 -0.8382)
			(end -1.651 -0.8382)
			(stroke
				(width 0.1524)
				(type default)
			)
			(layer "B.SilkS")
		)
		(fp_line
			(start -1.560576 0.7366)
			(end -1.560576 -0.7366)
			(stroke
				(width 0.1)
				(type default)
			)
			(layer "B.Fab")
		)
		(fp_line
			(start -1.524 0.7366)
			(end -1.560576 0.7366)
			(stroke
				(width 0.1)
				(type default)
			)
			(layer "B.Fab")
		)
		(fp_line
			(start 1.524 0.7366)
			(end -1.524 0.7366)
			(stroke
				(width 0.1)
				(type default)
			)
			(layer "B.Fab")
		)
		(fp_line
			(start 1.559814 0.7366)
			(end 1.524 0.7366)
			(stroke
				(width 0.1)
				(type default)
			)
			(layer "B.Fab")
		)
		(fp_line
			(start -1.560576 -0.7366)
			(end -1.524 -0.7366)
			(stroke
				(width 0.1)
				(type default)
			)
			(layer "B.Fab")
		)
		(fp_line
			(start -1.524 -0.7366)
			(end 1.524 -0.7366)
			(stroke
				(width 0.1)
				(type default)
			)
			(layer "B.Fab")
		)
		(fp_line
			(start 1.524 -0.7366)
			(end 1.559814 -0.7366)
			(stroke
				(width 0.1)
				(type default)
			)
			(layer "B.Fab")
		)
		(fp_line
			(start 1.559814 -0.7366)
			(end 1.559814 0.7366)
			(stroke
				(width 0.1)
				(type default)
			)
			(layer "B.Fab")
		)
		(pad "1" smd rect
			(at 0.94996 0 270)
			(size 1.1176 1.3716)
			(layers "B.Cu" "B.Mask" "B.Paste")
			(net "P52V_2")
		)
		(pad "2" smd rect
			(at -0.94996 0 270)
			(size 1.1176 1.3716)
			(layers "B.Cu" "B.Mask" "B.Paste")
			(net "P52V_HS2_UVLO_EN")
		)
	)
	(footprint ""
		(layer "B.Cu")
		(at 420.116 -35.052)
		(property "Reference" "R5931"
			(at 0 0 0)
			(layer "B.SilkS")
			(hide yes)
			(effects
				(font
					(size 1.27 1.27)
				)
				(justify mirror)
			)
		)
		(property "Value" ""
			(at 0 0 0)
			(layer "B.Fab")
			(effects
				(font
					(size 1.27 1.27)
				)
				(justify mirror)
			)
		)
		(duplicate_pad_numbers_are_jumpers no)
		(fp_line
			(start -0.7874 -0.4064)
			(end -0.7874 0.4064)
			(stroke
				(width 0.1524)
				(type default)
			)
			(layer "B.SilkS")
		)
		(fp_line
			(start -0.7874 0.4064)
			(end 0.7874 0.4064)
			(stroke
				(width 0.1524)
				(type default)
			)
			(layer "B.SilkS")
		)
		(fp_line
			(start 0.7874 -0.4064)
			(end -0.7874 -0.4064)
			(stroke
				(width 0.1524)
				(type default)
			)
			(layer "B.SilkS")
		)
		(fp_line
			(start 0.7874 0.4064)
			(end 0.7874 -0.4064)
			(stroke
				(width 0.1524)
				(type default)
			)
			(layer "B.SilkS")
		)
		(fp_line
			(start -0.67945 -0.3048)
			(end -0.67945 0.3048)
			(stroke
				(width 0.1)
				(type default)
			)
			(layer "B.Fab")
		)
		(fp_line
			(start -0.67945 0.3048)
			(end -0.120396 0.3048)
			(stroke
				(width 0.1)
				(type default)
			)
			(layer "B.Fab")
		)
		(fp_line
			(start -0.12065 -0.3048)
			(end -0.67945 -0.3048)
			(stroke
				(width 0.1)
				(type default)
			)
			(layer "B.Fab")
		)
		(fp_line
			(start -0.12065 -0.2794)
			(end -0.12065 -0.3048)
			(stroke
				(width 0.1)
				(type default)
			)
			(layer "B.Fab")
		)
		(fp_line
			(start -0.120396 0.2794)
			(end 0.12065 0.2794)
			(stroke
				(width 0.1)
				(type default)
			)
			(layer "B.Fab")
		)
		(fp_line
			(start -0.120396 0.3048)
			(end -0.120396 0.2794)
			(stroke
				(width 0.1)
				(type default)
			)
			(layer "B.Fab")
		)
		(fp_line
			(start 0.12065 -0.305054)
			(end 0.12065 -0.2794)
			(stroke
				(width 0.1)
				(type default)
			)
			(layer "B.Fab")
		)
		(fp_line
			(start 0.12065 -0.2794)
			(end -0.12065 -0.2794)
			(stroke
				(width 0.1)
				(type default)
			)
			(layer "B.Fab")
		)
		(fp_line
			(start 0.12065 0.2794)
			(end 0.12065 0.3048)
			(stroke
				(width 0.1)
				(type default)
			)
			(layer "B.Fab")
		)
		(fp_line
			(start 0.12065 0.3048)
			(end 0.67945 0.3048)
			(stroke
				(width 0.1)
				(type default)
			)
			(layer "B.Fab")
		)
		(fp_line
			(start 0.67945 -0.305054)
			(end 0.12065 -0.305054)
			(stroke
				(width 0.1)
				(type default)
			)
			(layer "B.Fab")
		)
		(fp_line
			(start 0.67945 0.3048)
			(end 0.67945 -0.305054)
			(stroke
				(width 0.1)
				(type default)
			)
			(layer "B.Fab")
		)
		(pad "1" smd circle
			(at 0.40005 0 180)
			(size 0 0)
			(layers "B.Cu" "B.Mask" "B.Paste")
			(net "P3V3_AUX")
		)
		(pad "2" smd circle
			(at -0.40005 0 180)
			(size 0 0)
			(layers "B.Cu" "B.Mask" "B.Paste")
			(net "PU_U39_PIN1")
		)
	)
	(footprint ""
		(layer "B.Cu")
		(at 276.3774 -84.201 90)
		(property "Reference" "PR18"
			(at 0 0 90)
			(layer "B.SilkS")
			(hide yes)
			(effects
				(font
					(size 1.27 1.27)
				)
				(justify mirror)
			)
		)
		(property "Value" ""
			(at 0 0 90)
			(layer "B.Fab")
			(effects
				(font
					(size 1.27 1.27)
				)
				(justify mirror)
			)
		)
		(duplicate_pad_numbers_are_jumpers no)
		(fp_line
			(start 1.651 -0.8382)
			(end -1.651 -0.8382)
			(stroke
				(width 0.1524)
				(type default)
			)
			(layer "B.SilkS")
		)
		(fp_line
			(start -1.651 -0.8382)
			(end -1.651 0.8382)
			(stroke
				(width 0.1524)
				(type default)
			)
			(layer "B.SilkS")
		)
		(fp_line
			(start 1.651 0.8382)
			(end 1.651 -0.8382)
			(stroke
				(width 0.1524)
				(type default)
			)
			(layer "B.SilkS")
		)
		(fp_line
			(start -1.651 0.8382)
			(end 1.651 0.8382)
			(stroke
				(width 0.1524)
				(type default)
			)
			(layer "B.SilkS")
		)
		(fp_line
			(start 1.559814 -0.7366)
			(end 1.559814 0.7366)
			(stroke
				(width 0.1)
				(type default)
			)
			(layer "B.Fab")
		)
		(fp_line
			(start 1.524 -0.7366)
			(end 1.559814 -0.7366)
			(stroke
				(width 0.1)
				(type default)
			)
			(layer "B.Fab")
		)
		(fp_line
			(start -1.524 -0.7366)
			(end 1.524 -0.7366)
			(stroke
				(width 0.1)
				(type default)
			)
			(layer "B.Fab")
		)
		(fp_line
			(start -1.560576 -0.7366)
			(end -1.524 -0.7366)
			(stroke
				(width 0.1)
				(type default)
			)
			(layer "B.Fab")
		)
		(fp_line
			(start 1.559814 0.7366)
			(end 1.524 0.7366)
			(stroke
				(width 0.1)
				(type default)
			)
			(layer "B.Fab")
		)
		(fp_line
			(start 1.524 0.7366)
			(end -1.524 0.7366)
			(stroke
				(width 0.1)
				(type default)
			)
			(layer "B.Fab")
		)
		(fp_line
			(start -1.524 0.7366)
			(end -1.560576 0.7366)
			(stroke
				(width 0.1)
				(type default)
			)
			(layer "B.Fab")
		)
		(fp_line
			(start -1.560576 0.7366)
			(end -1.560576 -0.7366)
			(stroke
				(width 0.1)
				(type default)
			)
			(layer "B.Fab")
		)
		(pad "1" smd rect
			(at 0.94996 0 90)
			(size 1.1176 1.3716)
			(layers "B.Cu" "B.Mask" "B.Paste")
			(net "P52V_1")
		)
		(pad "2" smd rect
			(at -0.94996 0 90)
			(size 1.1176 1.3716)
			(layers "B.Cu" "B.Mask" "B.Paste")
			(net "P52V_HS1_ISET")
		)
	)
)
